(kicad_pcb
	(version 20260206)
	(generator "pcbnew")
	(generator_version "10.0")
	(general
		(thickness 1.6)
		(legacy_teardrops no)
	)
	(paper "A4")
	(title_block
		(title "dpb — 14545-sa.0730WZS0815.brd")
		(comment 1 "Honey Badger (Wiwynn) / footprints 658-663 of 1066")
	)
	(layers
		(0 "F.Cu" signal "TOP")
		(4 "In1.Cu" signal "L2GND")
		(6 "In2.Cu" signal "L3")
		(8 "In3.Cu" signal "L4VCC")
		(10 "In4.Cu" signal "L5VCC")
		(12 "In5.Cu" signal "L6")
		(14 "In6.Cu" signal "L7GND")
		(2 "B.Cu" signal "BOTTOM")
		(9 "F.Adhes" user "F.Adhesive")
		(11 "B.Adhes" user "B.Adhesive")
		(13 "F.Paste" user "Package Geometry/Pastemask Top")
		(15 "B.Paste" user "Package Geometry/Pastemask Bottom")
		(5 "F.SilkS" user "Ref Des/Silkscreen Top")
		(7 "B.SilkS" user "Ref Des/Silkscreen Bottom")
		(1 "F.Mask" user "Board Geometry/Soldermask Top")
		(3 "B.Mask" user "Board Geometry/Soldermask Bottom")
		(17 "Dwgs.User" user "User.Drawings")
		(19 "Cmts.User" user "User.Comments")
		(21 "Eco1.User" user "User.Eco1")
		(23 "Eco2.User" user "User.Eco2")
		(25 "Edge.Cuts" user "Board Geometry/Outline")
		(27 "Margin" user)
		(31 "F.CrtYd" user "Package Geometry/Place Bound Top")
		(29 "B.CrtYd" user "Package Geometry/Place Bound Bottom")
		(35 "F.Fab" user "Ref Des/Assembly Top")
		(33 "B.Fab" user "Ref Des/Assembly Bottom")
	)
	(footprint ""
		(layer "F.Cu")
		(at 73.913746 -194.3227 90)
		(property "Reference" "U26"
			(at 0 0 90)
			(layer "F.SilkS")
			(hide yes)
			(effects
				(font
					(size 1.27 1.27)
				)
			)
		)
		(property "Value" "P2003EVG-GP"
			(at 0 -11.1252 90)
			(unlocked yes)
			(layer "F.Fab")
			(hide yes)
			(effects
				(font
					(size 1.016 1.016)
					(thickness 0.1524)
				)
			)
		)
		(property "Device Type" "SOIC8H79"
			(at 0 -12.6492 90)
			(unlocked yes)
			(layer "F.Fab")
			(hide yes)
			(effects
				(font
					(size 1.016 1.016)
					(thickness 0.1524)
				)
			)
		)
		(duplicate_pad_numbers_are_jumpers no)
		(fp_line
			(start 2.1336 -1.4224)
			(end -2.7432 -1.4224)
			(stroke
				(width 0.1524)
				(type default)
			)
			(layer "F.SilkS")
		)
		(fp_line
			(start -2.7432 -1.4224)
			(end -2.7432 1.4224)
			(stroke
				(width 0.1524)
				(type default)
			)
			(layer "F.SilkS")
		)
		(fp_line
			(start -2.7432 -0.508)
			(end -2.2352 0)
			(stroke
				(width 0.1524)
				(type default)
			)
			(layer "F.SilkS")
		)
		(fp_line
			(start -2.2352 0)
			(end -2.7432 0.508)
			(stroke
				(width 0.1524)
				(type default)
			)
			(layer "F.SilkS")
		)
		(fp_line
			(start 2.1336 1.4224)
			(end 2.1336 -1.4224)
			(stroke
				(width 0.1524)
				(type default)
			)
			(layer "F.SilkS")
		)
		(fp_line
			(start -2.7432 1.4224)
			(end 2.1336 1.4224)
			(stroke
				(width 0.1524)
				(type default)
			)
			(layer "F.SilkS")
		)
		(fp_line
			(start -2.6162 3.429)
			(end -2.6162 1.4732)
			(stroke
				(width 0.4064)
				(type default)
			)
			(layer "F.SilkS")
		)
		(fp_poly
			(pts
				(xy 2.2098 -1.4224) (xy 2.2098 1.4224) (xy -2.2225 1.4224) (xy -2.2225 -1.4224)
			)
			(stroke
				(width 0)
				(type default)
			)
			(fill yes)
			(layer "F.SilkS")
		)
		(fp_rect
			(start -2.4511 2.9972)
			(end 2.4511 -2.9972)
			(stroke
				(width 0)
				(type default)
			)
			(fill no)
			(layer "F.CrtYd")
		)
		(fp_poly
			(pts
				(xy -2.8194 3.6322) (xy -2.8194 -3.6322) (xy 2.8194 -3.6322) (xy 2.8194 -2.2987) (xy 2.4511 -2.2987)
				(xy 2.4511 -2.9972) (xy -2.4511 -2.9972) (xy -2.4511 2.9972) (xy 2.4511 2.9972) (xy 2.4511 -2.286)
				(xy 2.8194 -2.286) (xy 2.8194 3.6322)
			)
			(stroke
				(width 0)
				(type default)
			)
			(fill no)
			(layer "F.CrtYd")
		)
		(fp_rect
			(start -2.8194 3.6322)
			(end 2.8194 -3.6322)
			(stroke
				(width 0)
				(type default)
			)
			(fill no)
			(layer "F.Fab")
		)
		(pad "1" smd rect
			(at -1.905 2.54 90)
			(size 0.635 1.651)
			(layers "F.Cu" "F.Mask" "F.Paste")
			(net "P12V")
		)
		(pad "2" smd rect
			(at -0.635 2.54 90)
			(size 0.635 1.651)
			(layers "F.Cu" "F.Mask" "F.Paste")
			(net "P12V")
		)
		(pad "3" smd rect
			(at 0.635 2.54 90)
			(size 0.635 1.651)
			(layers "F.Cu" "F.Mask" "F.Paste")
			(net "P12V")
		)
		(pad "4" smd rect
			(at 1.905 2.54 90)
			(size 0.635 1.651)
			(layers "F.Cu" "F.Mask" "F.Paste")
			(net "SW_HDD8_N")
		)
		(pad "5" smd rect
			(at 1.905 -2.54 90)
			(size 0.635 1.651)
			(layers "F.Cu" "F.Mask" "F.Paste")
			(net "P12V_HDD8")
		)
		(pad "6" smd rect
			(at 0.635 -2.54 90)
			(size 0.635 1.651)
			(layers "F.Cu" "F.Mask" "F.Paste")
			(net "P12V_HDD8")
		)
		(pad "7" smd rect
			(at -0.635 -2.54 90)
			(size 0.635 1.651)
			(layers "F.Cu" "F.Mask" "F.Paste")
			(net "P12V_HDD8")
		)
		(pad "8" smd rect
			(at -1.905 -2.54 90)
			(size 0.635 1.651)
			(layers "F.Cu" "F.Mask" "F.Paste")
			(net "P12V_HDD8")
		)
	)
	(footprint ""
		(layer "F.Cu")
		(at 38.7604 -427.4566 180)
		(property "Reference" "R396"
			(at 0 0 180)
			(layer "F.SilkS")
			(hide yes)
			(effects
				(font
					(size 1.27 1.27)
				)
			)
		)
		(property "Value" "0R2J-2-GP"
			(at 0.064008 -3.993896 180)
			(unlocked yes)
			(layer "F.Fab")
			(hide yes)
			(effects
				(font
					(size 1.016 1.016)
					(thickness 0.1524)
				)
			)
		)
		(property "Device Type" "R402H16"
			(at 0.064008 -5.517896 180)
			(unlocked yes)
			(layer "F.Fab")
			(hide yes)
			(effects
				(font
					(size 1.016 1.016)
					(thickness 0.1524)
				)
			)
		)
		(duplicate_pad_numbers_are_jumpers no)
		(fp_line
			(start 0.508 -0.9398)
			(end -0.508 -0.9398)
			(stroke
				(width 0.1524)
				(type default)
			)
			(layer "F.SilkS")
		)
		(fp_line
			(start -0.508 -0.9398)
			(end -0.508 0.9398)
			(stroke
				(width 0.1524)
				(type default)
			)
			(layer "F.SilkS")
		)
		(fp_rect
			(start -0.508 0.9398)
			(end 0.508 -0.9398)
			(stroke
				(width 0)
				(type default)
			)
			(fill no)
			(layer "F.CrtYd")
		)
		(fp_rect
			(start -0.508 0.9398)
			(end 0.508 -0.9398)
			(stroke
				(width 0)
				(type default)
			)
			(fill no)
			(layer "F.Fab")
		)
		(pad "1" smd custom
			(at 0 -0.4445 180)
			(size 0.1397 0.1397)
			(layers "F.Cu" "F.Mask" "F.Paste")
			(net "HDD_PRSNT_NET10")
			(options
				(clearance outline)
				(anchor circle)
			)
			(primitives
				(gr_poly
					(pts
						(arc
							(start -0.1778 -0.2794)
							(mid -0.249642 -0.249642)
							(end -0.2794 -0.1778)
						)
						(arc
							(start -0.2794 0.1778)
							(mid -0.249642 0.249642)
							(end -0.1778 0.2794)
						)
						(arc
							(start 0.1778 0.2794)
							(mid 0.249642 0.249642)
							(end 0.2794 0.1778)
						)
						(arc
							(start 0.2794 -0.1778)
							(mid 0.249642 -0.249642)
							(end 0.1778 -0.2794)
						)
					)
					(width 0)
					(fill yes)
				)
			)
		)
		(pad "2" smd custom
			(at 0 0.4445 180)
			(size 0.1397 0.1397)
			(layers "F.Cu" "F.Mask" "F.Paste")
			(net "HDD10_LED_B")
			(options
				(clearance outline)
				(anchor circle)
			)
			(primitives
				(gr_poly
					(pts
						(arc
							(start -0.1778 -0.2794)
							(mid -0.249642 -0.249642)
							(end -0.2794 -0.1778)
						)
						(arc
							(start -0.2794 0.1778)
							(mid -0.249642 0.249642)
							(end -0.1778 0.2794)
						)
						(arc
							(start 0.1778 0.2794)
							(mid 0.249642 0.249642)
							(end 0.2794 0.1778)
						)
						(arc
							(start 0.2794 -0.1778)
							(mid 0.249642 -0.249642)
							(end 0.1778 -0.2794)
						)
					)
					(width 0)
					(fill yes)
				)
			)
		)
	)
	(footprint ""
		(layer "F.Cu")
		(at 26.880312 -345.046808 90)
		(property "Reference" "C279"
			(at 0 0 90)
			(layer "F.SilkS")
			(hide yes)
			(effects
				(font
					(size 1.27 1.27)
				)
			)
		)
		(property "Value" "SCD01U50V2KX-1GP"
			(at 1.1811 -2.7051 90)
			(unlocked yes)
			(layer "F.Fab")
			(hide yes)
			(effects
				(font
					(size 1.016 1.016)
					(thickness 0.1524)
				)
			)
		)
		(property "Device Type" "C402H22"
			(at 1.1811 -4.2291 90)
			(unlocked yes)
			(layer "F.Fab")
			(hide yes)
			(effects
				(font
					(size 1.016 1.016)
					(thickness 0.1524)
				)
			)
		)
		(duplicate_pad_numbers_are_jumpers no)
		(fp_rect
			(start -0.4318 0.9525)
			(end 0.4318 -0.9525)
			(stroke
				(width 0)
				(type default)
			)
			(fill no)
			(layer "F.CrtYd")
		)
		(fp_rect
			(start -0.4318 0.9525)
			(end 0.4318 -0.9525)
			(stroke
				(width 0)
				(type default)
			)
			(fill no)
			(layer "F.Fab")
		)
		(pad "1" smd custom
			(at 0 -0.4445 90)
			(size 0.1524 0.1524)
			(layers "F.Cu" "F.Mask" "F.Paste")
			(net "SAS2X28_DRIVE_RX_P_A11")
			(options
				(clearance outline)
				(anchor circle)
			)
			(primitives
				(gr_poly
					(pts
						(arc
							(start 0.3048 -0.2032)
							(mid 0.275042 -0.275042)
							(end 0.2032 -0.3048)
						)
						(arc
							(start -0.2032 -0.3048)
							(mid -0.275042 -0.275042)
							(end -0.3048 -0.2032)
						)
						(arc
							(start -0.3048 0.2032)
							(mid -0.275042 0.275042)
							(end -0.2032 0.3048)
						)
						(arc
							(start 0.2032 0.3048)
							(mid 0.275042 0.275042)
							(end 0.3048 0.2032)
						)
					)
					(width 0)
					(fill yes)
				)
			)
		)
		(pad "2" smd custom
			(at 0 0.4445 90)
			(size 0.1524 0.1524)
			(layers "F.Cu" "F.Mask" "F.Paste")
			(net "SAS2X28_A_HDD11_RX_+")
			(options
				(clearance outline)
				(anchor circle)
			)
			(primitives
				(gr_poly
					(pts
						(arc
							(start 0.3048 -0.2032)
							(mid 0.275042 -0.275042)
							(end 0.2032 -0.3048)
						)
						(arc
							(start -0.2032 -0.3048)
							(mid -0.275042 -0.275042)
							(end -0.3048 -0.2032)
						)
						(arc
							(start -0.3048 0.2032)
							(mid -0.275042 0.275042)
							(end -0.2032 0.3048)
						)
						(arc
							(start 0.2032 0.3048)
							(mid 0.275042 0.275042)
							(end 0.3048 0.2032)
						)
					)
					(width 0)
					(fill yes)
				)
			)
		)
	)
	(footprint ""
		(layer "F.Cu")
		(at 60.908946 -291.2491)
		(property "Reference" "Q15"
			(at 0 0 0)
			(layer "F.SilkS")
			(hide yes)
			(effects
				(font
					(size 1.27 1.27)
				)
			)
		)
		(property "Value" "AO4406AL-GP"
			(at -3.707384 -1.5367 0)
			(unlocked yes)
			(layer "F.Fab")
			(hide yes)
			(effects
				(font
					(size 1.016 1.016)
					(thickness 0.1524)
				)
			)
		)
		(property "Device Type" "SOIC8H69"
			(at -3.707384 -3.0607 0)
			(unlocked yes)
			(layer "F.Fab")
			(hide yes)
			(effects
				(font
					(size 1.016 1.016)
					(thickness 0.1524)
				)
			)
		)
		(duplicate_pad_numbers_are_jumpers no)
		(fp_line
			(start -2.7432 -1.4224)
			(end -2.7432 1.4224)
			(stroke
				(width 0.1524)
				(type default)
			)
			(layer "F.SilkS")
		)
		(fp_line
			(start -2.7432 1.4224)
			(end -2.6416 1.4224)
			(stroke
				(width 0.1524)
				(type default)
			)
			(layer "F.SilkS")
		)
		(fp_line
			(start -2.7432 1.4224)
			(end 2.1336 1.4224)
			(stroke
				(width 0.1524)
				(type default)
			)
			(layer "F.SilkS")
		)
		(fp_line
			(start -2.7178 -0.508)
			(end -2.1844 -0.0508)
			(stroke
				(width 0.1524)
				(type default)
			)
			(layer "F.SilkS")
		)
		(fp_line
			(start -2.6289 3.4417)
			(end -2.6289 1.4732)
			(stroke
				(width 0.381)
				(type default)
			)
			(layer "F.SilkS")
		)
		(fp_line
			(start -2.1844 -0.0508)
			(end -2.7178 0.508)
			(stroke
				(width 0.1524)
				(type default)
			)
			(layer "F.SilkS")
		)
		(fp_line
			(start 2.1336 -1.4224)
			(end -2.7432 -1.4224)
			(stroke
				(width 0.1524)
				(type default)
			)
			(layer "F.SilkS")
		)
		(fp_line
			(start 2.1336 1.4224)
			(end 2.1336 -1.4224)
			(stroke
				(width 0.1524)
				(type default)
			)
			(layer "F.SilkS")
		)
		(fp_poly
			(pts
				(xy -2.2098 -1.4224) (xy -2.2098 1.4224) (xy 2.2098 1.4224) (xy 2.2098 -1.4224)
			)
			(stroke
				(width 0)
				(type default)
			)
			(fill yes)
			(layer "F.SilkS")
		)
		(fp_rect
			(start -2.450084 2.999994)
			(end 2.450084 -2.999994)
			(stroke
				(width 0)
				(type default)
			)
			(fill no)
			(layer "F.CrtYd")
		)
		(fp_poly
			(pts
				(xy -2.8194 3.6322) (xy -2.8194 -3.6322) (xy 2.8194 -3.6322) (xy 2.8194 1.18364) (xy 2.450084 1.18364)
				(xy 2.450084 -2.999994) (xy -2.450084 -2.999994) (xy -2.450084 2.999994) (xy 2.450084 2.999994)
				(xy 2.450084 1.18618) (xy 2.8194 1.18618) (xy 2.8194 3.6322)
			)
			(stroke
				(width 0)
				(type default)
			)
			(fill no)
			(layer "F.CrtYd")
		)
		(fp_rect
			(start -2.8194 3.6322)
			(end 2.8194 -3.6322)
			(stroke
				(width 0)
				(type default)
			)
			(fill no)
			(layer "F.Fab")
		)
		(pad "1" smd rect
			(at -1.905 2.54)
			(size 0.635 1.651)
			(layers "F.Cu" "F.Mask" "F.Paste")
			(net "P5V_HDD7")
		)
		(pad "2" smd rect
			(at -0.635 2.54)
			(size 0.635 1.651)
			(layers "F.Cu" "F.Mask" "F.Paste")
			(net "P5V_HDD7")
		)
		(pad "3" smd rect
			(at 0.635 2.54)
			(size 0.635 1.651)
			(layers "F.Cu" "F.Mask" "F.Paste")
			(net "P5V_HDD7")
		)
		(pad "4" smd rect
			(at 1.905 2.54)
			(size 0.635 1.651)
			(layers "F.Cu" "F.Mask" "F.Paste")
			(net "SW_HDD7_P")
		)
		(pad "5" smd rect
			(at 1.905 -2.54)
			(size 0.635 1.651)
			(layers "F.Cu" "F.Mask" "F.Paste")
			(net "P5VB")
		)
		(pad "6" smd rect
			(at 0.635 -2.54)
			(size 0.635 1.651)
			(layers "F.Cu" "F.Mask" "F.Paste")
			(net "P5VB")
		)
		(pad "7" smd rect
			(at -0.635 -2.54)
			(size 0.635 1.651)
			(layers "F.Cu" "F.Mask" "F.Paste")
			(net "P5VB")
		)
		(pad "8" smd rect
			(at -1.905 -2.54)
			(size 0.635 1.651)
			(layers "F.Cu" "F.Mask" "F.Paste")
			(net "P5VB")
		)
	)
	(footprint ""
		(layer "F.Cu")
		(at 42.500042 -247.160034 180)
		(property "Reference" "LED8"
			(at 0 0 180)
			(layer "F.SilkS")
			(hide yes)
			(effects
				(font
					(size 1.27 1.27)
				)
			)
		)
		(property "Value" "LED-RB-4-GP"
			(at 5.88899 1.80848 180)
			(unlocked yes)
			(layer "F.Fab")
			(hide yes)
			(effects
				(font
					(size 1.016 1.016)
					(thickness 0.1524)
				)
			)
		)
		(property "Device Type" "LED1613-4PH20"
			(at 5.88899 0.28448 180)
			(unlocked yes)
			(layer "F.Fab")
			(hide yes)
			(effects
				(font
					(size 1.016 1.016)
					(thickness 0.1524)
				)
			)
		)
		(duplicate_pad_numbers_are_jumpers no)
		(fp_line
			(start 1.4478 0.9652)
			(end -1.4478 0.9652)
			(stroke
				(width 0.1524)
				(type default)
			)
			(layer "F.SilkS")
		)
		(fp_line
			(start 1.4478 -0.9652)
			(end 1.4478 0.9652)
			(stroke
				(width 0.1524)
				(type default)
			)
			(layer "F.SilkS")
		)
		(fp_line
			(start -1.4478 0.9652)
			(end -1.4478 -0.9652)
			(stroke
				(width 0.1524)
				(type default)
			)
			(layer "F.SilkS")
		)
		(fp_line
			(start -1.4478 0.9652)
			(end -1.4478 -0.9652)
			(stroke
				(width 0.508)
				(type default)
			)
			(layer "F.SilkS")
		)
		(fp_line
			(start -1.4478 -0.9652)
			(end 1.4478 -0.9652)
			(stroke
				(width 0.1524)
				(type default)
			)
			(layer "F.SilkS")
		)
		(fp_rect
			(start -0.8001 0.6477)
			(end 0.8001 -0.6477)
			(stroke
				(width 0)
				(type default)
			)
			(fill no)
			(layer "F.CrtYd")
		)
		(fp_poly
			(pts
				(xy -1.7018 1.2192) (xy -1.7018 -0.06223) (xy -0.8001 -0.06223) (xy -0.8001 0.6477) (xy 0.8001 0.6477)
				(xy 0.8001 -0.6477) (xy -0.8001 -0.6477) (xy -0.8001 -0.0635) (xy -1.7018 -0.0635) (xy -1.7018 -1.2192)
				(xy 1.7018 -1.2192) (xy 1.7018 1.2192)
			)
			(stroke
				(width 0)
				(type default)
			)
			(fill no)
			(layer "F.CrtYd")
		)
		(fp_rect
			(start -1.7018 1.2192)
			(end 1.7018 -1.2192)
			(stroke
				(width 0)
				(type default)
			)
			(fill no)
			(layer "F.Fab")
		)
		(pad "1" smd rect
			(at -0.73025 0.4064 180)
			(size 0.9144 0.6096)
			(layers "F.Cu" "F.Mask" "F.Paste")
			(net "DRV_ACT_NET7")
		)
		(pad "2" smd rect
			(at -0.73025 -0.4064 180)
			(size 0.9144 0.6096)
			(layers "F.Cu" "F.Mask" "F.Paste")
			(net "FLT_NET_HDD7")
		)
		(pad "3" smd rect
			(at 0.73025 -0.4064 180)
			(size 0.9144 0.6096)
			(layers "F.Cu" "F.Mask" "F.Paste")
			(net "FLT_HDD7")
		)
		(pad "4" smd rect
			(at 0.73025 0.4064 180)
			(size 0.9144 0.6096)
			(layers "F.Cu" "F.Mask" "F.Paste")
			(net "DRV_ACT_7")
		)
	)
	(footprint ""
		(layer "F.Cu")
		(at 20.192746 -52.9717 -90)
		(property "Reference" "R299"
			(at 0 0 270)
			(layer "F.SilkS")
			(hide yes)
			(effects
				(font
					(size 1.27 1.27)
				)
			)
		)
		(property "Value" "330R2F-GP"
			(at 0.064008 -3.993896 270)
			(unlocked yes)
			(layer "F.Fab")
			(hide yes)
			(effects
				(font
					(size 1.016 1.016)
					(thickness 0.1524)
				)
			)
		)
		(property "Device Type" "R402H16"
			(at 0.064008 -5.517896 270)
			(unlocked yes)
			(layer "F.Fab")
			(hide yes)
			(effects
				(font
					(size 1.016 1.016)
					(thickness 0.1524)
				)
			)
		)
		(duplicate_pad_numbers_are_jumpers no)
		(fp_line
			(start -0.508 -0.9398)
			(end -0.508 0.9398)
			(stroke
				(width 0.1524)
				(type default)
			)
			(layer "F.SilkS")
		)
		(fp_line
			(start 0.508 -0.9398)
			(end -0.508 -0.9398)
			(stroke
				(width 0.1524)
				(type default)
			)
			(layer "F.SilkS")
		)
		(fp_rect
			(start -0.508 0.9398)
			(end 0.508 -0.9398)
			(stroke
				(width 0)
				(type default)
			)
			(fill no)
			(layer "F.CrtYd")
		)
		(fp_rect
			(start -0.508 0.9398)
			(end 0.508 -0.9398)
			(stroke
				(width 0)
				(type default)
			)
			(fill no)
			(layer "F.Fab")
		)
		(pad "1" smd custom
			(at 0 -0.4445 270)
			(size 0.1397 0.1397)
			(layers "F.Cu" "F.Mask" "F.Paste")
			(net "P3V3_HDD14_LED")
			(options
				(clearance outline)
				(anchor circle)
			)
			(primitives
				(gr_poly
					(pts
						(arc
							(start -0.1778 -0.2794)
							(mid -0.249642 -0.249642)
							(end -0.2794 -0.1778)
						)
						(arc
							(start -0.2794 0.1778)
							(mid -0.249642 0.249642)
							(end -0.1778 0.2794)
						)
						(arc
							(start 0.1778 0.2794)
							(mid 0.249642 0.249642)
							(end 0.2794 0.1778)
						)
						(arc
							(start 0.2794 -0.1778)
							(mid 0.249642 -0.249642)
							(end 0.1778 -0.2794)
						)
					)
					(width 0)
					(fill yes)
				)
			)
		)
		(pad "2" smd custom
			(at 0 0.4445 270)
			(size 0.1397 0.1397)
			(layers "F.Cu" "F.Mask" "F.Paste")
			(net "FLT_HDD14")
			(options
				(clearance outline)
				(anchor circle)
			)
			(primitives
				(gr_poly
					(pts
						(arc
							(start -0.1778 -0.2794)
							(mid -0.249642 -0.249642)
							(end -0.2794 -0.1778)
						)
						(arc
							(start -0.2794 0.1778)
							(mid -0.249642 0.249642)
							(end -0.1778 0.2794)
						)
						(arc
							(start 0.1778 0.2794)
							(mid 0.249642 0.249642)
							(end 0.2794 0.1778)
						)
						(arc
							(start 0.2794 -0.1778)
							(mid 0.249642 -0.249642)
							(end 0.1778 -0.2794)
						)
					)
					(width 0)
					(fill yes)
				)
			)
		)
	)
)
